(kicad_pcb
	(version 20260206)
	(generator "pcbnew")
	(generator_version "10.0")
	(general
		(thickness 1.6)
		(legacy_teardrops no)
	)
	(paper "A4")
	(title_block
		(title "v1-chassis-manager — T6M_CM_d_v01_1031_1645.brd")
		(comment 1 "Open CloudServer (Microsoft) / footprints 678-684 of 2512")
	)
	(layers
		(0 "F.Cu" signal "TOP")
		(4 "In1.Cu" signal "GND1")
		(6 "In2.Cu" signal "IN1")
		(8 "In3.Cu" signal "VCC1")
		(10 "In4.Cu" signal "VCC2")
		(12 "In5.Cu" signal "GND2")
		(14 "In6.Cu" signal "IN2")
		(16 "In7.Cu" signal "IN3")
		(18 "In8.Cu" signal "GND3")
		(2 "B.Cu" signal "BOTTOM")
		(9 "F.Adhes" user "F.Adhesive")
		(11 "B.Adhes" user "B.Adhesive")
		(13 "F.Paste" user "Package Geometry/Pastemask Top")
		(15 "B.Paste" user "Package Geometry/Pastemask Bottom")
		(5 "F.SilkS" user "Ref Des/Silkscreen Top")
		(7 "B.SilkS" user "Ref Des/Silkscreen Bottom")
		(1 "F.Mask" user "Board Geometry/Soldermask Top")
		(3 "B.Mask" user "Board Geometry/Soldermask Bottom")
		(17 "Dwgs.User" user "User.Drawings")
		(19 "Cmts.User" user "User.Comments")
		(21 "Eco1.User" user "User.Eco1")
		(23 "Eco2.User" user "User.Eco2")
		(25 "Edge.Cuts" user "Board Geometry/Outline")
		(27 "Margin" user)
		(31 "F.CrtYd" user "Package Geometry/Place Bound Top")
		(29 "B.CrtYd" user "Package Geometry/Place Bound Bottom")
		(35 "F.Fab" user "Ref Des/Assembly Top")
		(33 "B.Fab" user "Ref Des/Assembly Bottom")
	)
	(footprint ""
		(layer "F.Cu")
		(at 15.21968 -43.923204 90)
		(property "Reference" "C502"
			(at -7.91337 -0.69342 90)
			(unlocked yes)
			(layer "F.SilkS")
			(effects
				(font
					(size 0.7874 0.5842)
					(thickness 0.1524)
				)
			)
		)
		(property "Value" ""
			(at 0 0 90)
			(layer "F.Fab")
			(effects
				(font
					(size 1.27 1.27)
				)
			)
		)
		(duplicate_pad_numbers_are_jumpers no)
		(fp_line
			(start 1.2954 -0.5842)
			(end 1.2954 0.5842)
			(stroke
				(width 0.1524)
				(type default)
			)
			(layer "F.SilkS")
		)
		(fp_line
			(start 0 -0.5842)
			(end 0 0.5842)
			(stroke
				(width 0.1524)
				(type default)
			)
			(layer "F.SilkS")
		)
		(fp_line
			(start -1.2954 -0.5842)
			(end 1.2954 -0.5842)
			(stroke
				(width 0.1524)
				(type default)
			)
			(layer "F.SilkS")
		)
		(fp_line
			(start 1.2954 0.5842)
			(end -1.2954 0.5842)
			(stroke
				(width 0.1524)
				(type default)
			)
			(layer "F.SilkS")
		)
		(fp_line
			(start -1.2954 0.5842)
			(end -1.2954 -0.5842)
			(stroke
				(width 0.1524)
				(type default)
			)
			(layer "F.SilkS")
		)
		(fp_poly
			(pts
				(xy 0.8636 -0.4572) (xy 0.8636 -0.3556) (xy 1.143 -0.3556) (xy 1.143 0.3556) (xy 0.8636 0.3556)
				(xy 0.8636 0.4572) (xy -0.8636 0.4572) (xy -0.8636 0.3556) (xy -1.143 0.3556) (xy -1.143 -0.3556)
				(xy -0.8636 -0.3556) (xy -0.8636 -0.4572)
			)
			(stroke
				(width 0)
				(type default)
			)
			(fill no)
			(layer "F.CrtYd")
		)
		(fp_line
			(start 0.884936 -0.504952)
			(end 0.884936 0.504952)
			(stroke
				(width 0.1)
				(type default)
			)
			(layer "F.Fab")
		)
		(fp_line
			(start -0.884936 -0.504952)
			(end 0.884936 -0.504952)
			(stroke
				(width 0.1)
				(type default)
			)
			(layer "F.Fab")
		)
		(fp_line
			(start 0.884936 0.504952)
			(end -0.884936 0.504952)
			(stroke
				(width 0.1)
				(type default)
			)
			(layer "F.Fab")
		)
		(fp_line
			(start -0.884936 0.504952)
			(end -0.884936 -0.504952)
			(stroke
				(width 0.1)
				(type default)
			)
			(layer "F.Fab")
		)
		(pad "1" smd rect
			(at 0.7366 0 180)
			(size 0.7112 0.8128)
			(layers "F.Cu" "F.Mask" "F.Paste")
			(net "CRT_R")
		)
		(pad "2" smd rect
			(at -0.7366 0 180)
			(size 0.7112 0.8128)
			(layers "F.Cu" "F.Mask" "F.Paste")
			(net "GND")
		)
	)
	(footprint ""
		(layer "F.Cu")
		(at 83.460082 -88.702134)
		(property "Reference" "R136"
			(at -1.235202 1.075944 0)
			(unlocked yes)
			(layer "F.SilkS")
			(effects
				(font
					(size 0.635 0.4064)
					(thickness 0.1524)
				)
				(justify left)
			)
		)
		(property "Value" ""
			(at 0 0 0)
			(layer "F.Fab")
			(effects
				(font
					(size 1.27 1.27)
				)
			)
		)
		(duplicate_pad_numbers_are_jumpers no)
		(fp_line
			(start -0.7874 -0.4064)
			(end 0.7874 -0.4064)
			(stroke
				(width 0.1524)
				(type default)
			)
			(layer "F.SilkS")
		)
		(fp_line
			(start -0.7874 0.4064)
			(end -0.7874 -0.4064)
			(stroke
				(width 0.1524)
				(type default)
			)
			(layer "F.SilkS")
		)
		(fp_line
			(start 0.7874 -0.4064)
			(end 0.7874 0.4064)
			(stroke
				(width 0.1524)
				(type default)
			)
			(layer "F.SilkS")
		)
		(fp_line
			(start 0.7874 0.4064)
			(end -0.7874 0.4064)
			(stroke
				(width 0.1524)
				(type default)
			)
			(layer "F.SilkS")
		)
		(fp_poly
			(pts
				(xy -0.508 0.2794) (xy -0.508 0.2286) (xy -0.635 0.2286) (xy -0.635 -0.254) (xy -0.5334 -0.254)
				(xy -0.5334 -0.2794) (xy 0.5334 -0.2794) (xy 0.5334 -0.254) (xy 0.635 -0.254) (xy 0.635 0.254) (xy 0.5334 0.254)
				(xy 0.5334 0.2794)
			)
			(stroke
				(width 0)
				(type default)
			)
			(fill no)
			(layer "F.CrtYd")
		)
		(pad "1" smd rect
			(at 0.40005 0)
			(size 0.4572 0.508)
			(layers "F.Cu" "F.Mask" "F.Paste")
			(net "P3V3_SUS_NODE1")
		)
		(pad "2" smd rect
			(at -0.40005 0)
			(size 0.4572 0.508)
			(layers "F.Cu" "F.Mask" "F.Paste")
			(net "FM_CPU_NODE1_SLPRDY_L")
		)
	)
	(footprint ""
		(layer "F.Cu")
		(at 189.221872 -7.457694)
		(property "Reference" "J32"
			(at -0.921766 -2.167382 0)
			(unlocked yes)
			(layer "F.SilkS")
			(effects
				(font
					(size 0.7874 0.5842)
					(thickness 0.1524)
				)
				(justify left)
			)
		)
		(property "Value" ""
			(at 0 0 0)
			(layer "F.Fab")
			(effects
				(font
					(size 1.27 1.27)
				)
			)
		)
		(duplicate_pad_numbers_are_jumpers no)
		(fp_line
			(start -2.739898 -1.27)
			(end -2.739898 1.27)
			(stroke
				(width 0.1524)
				(type default)
			)
			(layer "F.SilkS")
		)
		(fp_line
			(start -2.739898 1.27)
			(end -2.690114 1.27)
			(stroke
				(width 0.1524)
				(type default)
			)
			(layer "F.SilkS")
		)
		(fp_line
			(start -2.739898 1.27)
			(end 2.739898 1.27)
			(stroke
				(width 0.1524)
				(type default)
			)
			(layer "F.SilkS")
		)
		(fp_line
			(start 2.739898 -1.27)
			(end -2.739898 -1.27)
			(stroke
				(width 0.1524)
				(type default)
			)
			(layer "F.SilkS")
		)
		(fp_line
			(start 2.739898 1.27)
			(end 2.739898 -1.27)
			(stroke
				(width 0.1524)
				(type default)
			)
			(layer "F.SilkS")
		)
		(fp_poly
			(pts
				(xy -1.2192 1.7653) (xy -1.9558 3.5687) (xy -0.5842 3.5687)
			)
			(stroke
				(width 0)
				(type default)
			)
			(fill yes)
			(layer "F.SilkS")
		)
		(fp_rect
			(start -2.1844 0.9144)
			(end 2.1844 -0.9144)
			(stroke
				(width 0)
				(type default)
			)
			(fill no)
			(layer "B.CrtYd")
		)
		(fp_poly
			(pts
				(xy -2.739898 1.27) (xy 2.739898 1.27) (xy 2.739898 -1.27) (xy -2.739898 -1.27)
			)
			(stroke
				(width 0)
				(type default)
			)
			(fill no)
			(layer "F.CrtYd")
		)
		(fp_line
			(start -2.739898 -1.27)
			(end -2.739898 1.27)
			(stroke
				(width 0.1)
				(type default)
			)
			(layer "F.Fab")
		)
		(fp_line
			(start -2.739898 1.27)
			(end -2.690114 1.27)
			(stroke
				(width 0.1)
				(type default)
			)
			(layer "F.Fab")
		)
		(fp_line
			(start -2.739898 1.27)
			(end 2.739898 1.27)
			(stroke
				(width 0.1)
				(type default)
			)
			(layer "F.Fab")
		)
		(fp_line
			(start 2.739898 -1.27)
			(end -2.739898 -1.27)
			(stroke
				(width 0.1)
				(type default)
			)
			(layer "F.Fab")
		)
		(fp_line
			(start 2.739898 1.27)
			(end 2.739898 -1.27)
			(stroke
				(width 0.1)
				(type default)
			)
			(layer "F.Fab")
		)
		(fp_poly
			(pts
				(xy -1.2192 1.7653) (xy -1.9558 3.5687) (xy -0.5842 3.5687)
			)
			(stroke
				(width 0)
				(type default)
			)
			(fill yes)
			(layer "F.Fab")
		)
		(fp_text user "1"
			(at -1.916938 1.964944 0)
			(unlocked yes)
			(layer "F.SilkS")
			(effects
				(font
					(size 0.7874 0.5842)
					(thickness 0.1524)
				)
				(justify left)
			)
		)
		(fp_text user "2"
			(at 2.78638 -0.63373 0)
			(unlocked yes)
			(layer "F.SilkS")
			(effects
				(font
					(size 0.7874 0.5842)
					(thickness 0.1524)
				)
				(justify left)
			)
		)
		(fp_text user "1"
			(at -0.685292 -1.810766 0)
			(unlocked yes)
			(layer "B.SilkS")
			(effects
				(font
					(size 0.7874 0.5842)
					(thickness 0.1524)
				)
				(justify left mirror)
			)
		)
		(fp_text user "2"
			(at 1.589024 -1.810766 0)
			(unlocked yes)
			(layer "B.SilkS")
			(effects
				(font
					(size 0.7874 0.5842)
					(thickness 0.1524)
				)
				(justify left mirror)
			)
		)
		(fp_text user "1"
			(at -1.9431 -0.18669 0)
			(unlocked yes)
			(layer "B.Fab")
			(effects
				(font
					(size 1.6002 1.1938)
					(thickness 0.000001)
				)
				(justify left mirror)
			)
		)
		(fp_text user "2"
			(at 3.1369 -0.18669 0)
			(unlocked yes)
			(layer "B.Fab")
			(effects
				(font
					(size 1.6002 1.1938)
					(thickness 0.000001)
				)
				(justify left mirror)
			)
		)
		(fp_text user "1"
			(at -2.8829 2.48031 0)
			(unlocked yes)
			(layer "F.Fab")
			(effects
				(font
					(size 1.6002 1.1938)
					(thickness 0.000001)
				)
				(justify left)
			)
		)
		(fp_text user "2"
			(at 0.6731 2.48031 0)
			(unlocked yes)
			(layer "F.Fab")
			(effects
				(font
					(size 1.6002 1.1938)
					(thickness 0.000001)
				)
				(justify left)
			)
		)
		(pad "1" thru_hole rect
			(at -1.27 0)
			(size 1.7272 1.7272)
			(drill 1.2192)
			(layers "*.Cu" "*.Mask")
			(remove_unused_layers no)
			(net "TACKOVER_EN_N")
			(clearance 0)
			(padstack
				(mode front_inner_back)
				(layer "Inner"
					(shape circle)
					(size 1.7272 1.7272)
					(clearance 0)
				)
				(layer "B.Cu"
					(shape rect)
					(size 1.7272 1.7272)
					(clearance 0)
				)
			)
		)
		(pad "2" thru_hole circle
			(at 1.27 0)
			(size 1.7272 1.7272)
			(drill 1.2192)
			(layers "*.Cu" "*.Mask")
			(remove_unused_layers no)
			(net "GND")
			(clearance 0)
		)
	)
	(footprint ""
		(layer "F.Cu")
		(at 124.063252 -26.574242 90)
		(property "Reference" "C486"
			(at -5.330444 0.16637 90)
			(unlocked yes)
			(layer "F.SilkS")
			(effects
				(font
					(size 0.7874 0.5842)
					(thickness 0.1524)
				)
				(justify left)
			)
		)
		(property "Value" ""
			(at 0 0 90)
			(layer "F.Fab")
			(effects
				(font
					(size 1.27 1.27)
				)
			)
		)
		(duplicate_pad_numbers_are_jumpers no)
		(fp_line
			(start 0.7874 -0.4064)
			(end 0.7874 0.4064)
			(stroke
				(width 0.1524)
				(type default)
			)
			(layer "F.SilkS")
		)
		(fp_line
			(start -0.7874 -0.4064)
			(end 0.7874 -0.4064)
			(stroke
				(width 0.1524)
				(type default)
			)
			(layer "F.SilkS")
		)
		(fp_line
			(start 0 0.381)
			(end 0 -0.381)
			(stroke
				(width 0.1524)
				(type default)
			)
			(layer "F.SilkS")
		)
		(fp_line
			(start 0.7874 0.4064)
			(end -0.7874 0.4064)
			(stroke
				(width 0.1524)
				(type default)
			)
			(layer "F.SilkS")
		)
		(fp_line
			(start -0.7874 0.4064)
			(end -0.7874 -0.4064)
			(stroke
				(width 0.1524)
				(type default)
			)
			(layer "F.SilkS")
		)
		(fp_poly
			(pts
				(xy -0.5334 0.254) (xy -0.635 0.254) (xy -0.635 0.2286) (xy -0.635 -0.254) (xy -0.5334 -0.254) (xy -0.5334 -0.2794)
				(xy 0.5334 -0.2794) (xy 0.5334 -0.254) (xy 0.635 -0.254) (xy 0.635 0.254) (xy 0.5334 0.254) (xy 0.5334 0.2794)
				(xy -0.508 0.2794) (xy -0.5334 0.2794)
			)
			(stroke
				(width 0)
				(type default)
			)
			(fill no)
			(layer "F.CrtYd")
		)
		(pad "1" smd rect
			(at 0.40005 0 90)
			(size 0.4572 0.508)
			(layers "F.Cu" "F.Mask" "F.Paste")
			(net "SIO_VBAT")
		)
		(pad "2" smd rect
			(at -0.40005 0 90)
			(size 0.4572 0.508)
			(layers "F.Cu" "F.Mask" "F.Paste")
			(net "GND")
		)
	)
	(footprint ""
		(layer "F.Cu")
		(at 169.643552 -56.98109)
		(property "Reference" "R269"
			(at -6.518148 0.01524 0)
			(unlocked yes)
			(layer "F.SilkS")
			(effects
				(font
					(size 0.7874 0.5842)
					(thickness 0.1524)
				)
				(justify left)
			)
		)
		(property "Value" ""
			(at 0 0 0)
			(layer "F.Fab")
			(effects
				(font
					(size 1.27 1.27)
				)
			)
		)
		(duplicate_pad_numbers_are_jumpers no)
		(fp_line
			(start -0.7874 -0.4064)
			(end 0.7874 -0.4064)
			(stroke
				(width 0.1524)
				(type default)
			)
			(layer "F.SilkS")
		)
		(fp_line
			(start -0.7874 0.4064)
			(end -0.7874 -0.4064)
			(stroke
				(width 0.1524)
				(type default)
			)
			(layer "F.SilkS")
		)
		(fp_line
			(start 0.7874 -0.4064)
			(end 0.7874 0.4064)
			(stroke
				(width 0.1524)
				(type default)
			)
			(layer "F.SilkS")
		)
		(fp_line
			(start 0.7874 0.4064)
			(end -0.7874 0.4064)
			(stroke
				(width 0.1524)
				(type default)
			)
			(layer "F.SilkS")
		)
		(fp_poly
			(pts
				(xy -0.508 0.2794) (xy -0.508 0.2286) (xy -0.635 0.2286) (xy -0.635 -0.254) (xy -0.5334 -0.254)
				(xy -0.5334 -0.2794) (xy 0.5334 -0.2794) (xy 0.5334 -0.254) (xy 0.635 -0.254) (xy 0.635 0.254) (xy 0.5334 0.254)
				(xy 0.5334 0.2794)
			)
			(stroke
				(width 0)
				(type default)
			)
			(fill no)
			(layer "F.CrtYd")
		)
		(pad "1" smd rect
			(at 0.40005 0)
			(size 0.4572 0.508)
			(layers "F.Cu" "F.Mask" "F.Paste")
			(net "USB2_L_DN")
		)
		(pad "2" smd rect
			(at -0.40005 0)
			(size 0.4572 0.508)
			(layers "F.Cu" "F.Mask" "F.Paste")
			(net "USB2_DN")
		)
	)
	(footprint ""
		(layer "F.Cu")
		(at 167.369744 -91.326208 90)
		(property "Reference" "Y3"
			(at -2.329688 1.194308 0)
			(unlocked yes)
			(layer "F.SilkS")
			(effects
				(font
					(size 0.7874 0.5842)
					(thickness 0.1524)
				)
				(justify left)
			)
		)
		(property "Value" ""
			(at 0 0 90)
			(layer "F.Fab")
			(effects
				(font
					(size 1.27 1.27)
				)
			)
		)
		(duplicate_pad_numbers_are_jumpers no)
		(fp_line
			(start 1.700022 -0.700024)
			(end 1.3716 -0.700024)
			(stroke
				(width 0.1524)
				(type default)
			)
			(layer "F.SilkS")
		)
		(fp_line
			(start -1.397 -0.700024)
			(end -1.700022 -0.700024)
			(stroke
				(width 0.1524)
				(type default)
			)
			(layer "F.SilkS")
		)
		(fp_line
			(start -1.700022 -0.700024)
			(end -1.700022 4.499864)
			(stroke
				(width 0.1524)
				(type default)
			)
			(layer "F.SilkS")
		)
		(fp_line
			(start 1.700022 4.499864)
			(end 1.700022 -0.700024)
			(stroke
				(width 0.1524)
				(type default)
			)
			(layer "F.SilkS")
		)
		(fp_line
			(start 1.3589 4.499864)
			(end 1.700022 4.499864)
			(stroke
				(width 0.1524)
				(type default)
			)
			(layer "F.SilkS")
		)
		(fp_line
			(start -1.700022 4.499864)
			(end -1.397 4.499864)
			(stroke
				(width 0.1524)
				(type default)
			)
			(layer "F.SilkS")
		)
		(fp_poly
			(pts
				(xy 0.233172 -1.826768) (xy -0.436372 -1.826768) (xy -0.114554 -1.018032)
			)
			(stroke
				(width 0)
				(type default)
			)
			(fill yes)
			(layer "F.SilkS")
		)
		(fp_poly
			(pts
				(xy -1.700022 -0.700024) (xy -1.700022 4.499864) (xy -1.27 4.499864) (xy -1.27 4.77012) (xy 1.27 4.77012)
				(xy 1.27 4.499864) (xy 1.700022 4.499864) (xy 1.700022 -0.700024) (xy 1.27 -0.700024) (xy 1.27 -0.97028)
				(xy -1.27 -0.97028) (xy -1.27 -0.700024)
			)
			(stroke
				(width 0)
				(type default)
			)
			(fill no)
			(layer "F.CrtYd")
		)
		(fp_line
			(start 1.700022 -0.700024)
			(end 1.700022 4.499864)
			(stroke
				(width 0.1)
				(type default)
			)
			(layer "F.Fab")
		)
		(fp_line
			(start -1.700022 -0.700024)
			(end 1.700022 -0.700024)
			(stroke
				(width 0.1)
				(type default)
			)
			(layer "F.Fab")
		)
		(fp_line
			(start 1.700022 4.499864)
			(end -1.700022 4.499864)
			(stroke
				(width 0.1)
				(type default)
			)
			(layer "F.Fab")
		)
		(fp_line
			(start -1.700022 4.499864)
			(end -1.700022 -0.700024)
			(stroke
				(width 0.1)
				(type default)
			)
			(layer "F.Fab")
		)
		(fp_poly
			(pts
				(xy 0.233172 -1.826768) (xy -0.436372 -1.826768) (xy -0.114554 -1.018032)
			)
			(stroke
				(width 0)
				(type default)
			)
			(fill yes)
			(layer "F.Fab")
		)
		(fp_text user "1"
			(at 0.576072 -1.455928 0)
			(unlocked yes)
			(layer "F.SilkS")
			(effects
				(font
					(size 0.635 0.4064)
					(thickness 0.1524)
				)
				(justify left)
			)
		)
		(fp_text user "2"
			(at 0.456184 4.836414 0)
			(unlocked yes)
			(layer "F.SilkS")
			(effects
				(font
					(size 0.635 0.4064)
					(thickness 0.1524)
				)
				(justify left)
			)
		)
		(fp_text user "1"
			(at 0.627888 -1.32588 0)
			(unlocked yes)
			(layer "F.Fab")
			(effects
				(font
					(size 0.635 0.4064)
					(thickness 0.000001)
				)
				(justify left)
			)
		)
		(fp_text user "2"
			(at 0.048768 4.7498 0)
			(unlocked yes)
			(layer "F.Fab")
			(effects
				(font
					(size 0.635 0.4064)
					(thickness 0.000001)
				)
				(justify left)
			)
		)
		(pad "1" smd rect
			(at 0 0)
			(size 1.8034 2.413)
			(layers "F.Cu" "F.Mask" "F.Paste")
			(net "USB_NODE1_XTA2")
		)
		(pad "2" smd rect
			(at 0 3.800094)
			(size 1.8034 2.413)
			(layers "F.Cu" "F.Mask" "F.Paste")
			(net "USB_NODE1_XTA1")
		)
	)
	(footprint ""
		(layer "F.Cu")
		(at 111.87176 -169.577512 180)
		(property "Reference" "R667"
			(at 1.96088 10.468356 0)
			(unlocked yes)
			(layer "F.SilkS")
			(effects
				(font
					(size 0.7874 0.5842)
					(thickness 0.1524)
				)
				(justify left)
			)
		)
		(property "Value" ""
			(at 0 0 180)
			(layer "F.Fab")
			(effects
				(font
					(size 1.27 1.27)
				)
			)
		)
		(duplicate_pad_numbers_are_jumpers no)
		(fp_line
			(start 0.7874 0.4064)
			(end -0.7874 0.4064)
			(stroke
				(width 0.1524)
				(type default)
			)
			(layer "F.SilkS")
		)
		(fp_line
			(start 0.7874 -0.4064)
			(end 0.7874 0.4064)
			(stroke
				(width 0.1524)
				(type default)
			)
			(layer "F.SilkS")
		)
		(fp_line
			(start -0.7874 0.4064)
			(end -0.7874 -0.4064)
			(stroke
				(width 0.1524)
				(type default)
			)
			(layer "F.SilkS")
		)
		(fp_line
			(start -0.7874 -0.4064)
			(end 0.7874 -0.4064)
			(stroke
				(width 0.1524)
				(type default)
			)
			(layer "F.SilkS")
		)
		(fp_poly
			(pts
				(xy -0.508 0.2794) (xy -0.508 0.2286) (xy -0.635 0.2286) (xy -0.635 -0.254) (xy -0.5334 -0.254)
				(xy -0.5334 -0.2794) (xy 0.5334 -0.2794) (xy 0.5334 -0.254) (xy 0.635 -0.254) (xy 0.635 0.254) (xy 0.5334 0.254)
				(xy 0.5334 0.2794)
			)
			(stroke
				(width 0)
				(type default)
			)
			(fill no)
			(layer "F.CrtYd")
		)
		(pad "1" smd rect
			(at 0.40005 0 180)
			(size 0.4572 0.508)
			(layers "F.Cu" "F.Mask" "F.Paste")
			(net "P3V3_NODE1")
		)
		(pad "2" smd rect
			(at -0.40005 0 180)
			(size 0.4572 0.508)
			(layers "F.Cu" "F.Mask" "F.Paste")
			(net "I2C_PSU2_SCL_MOS")
		)
	)
)
